(kicad_pcb
	(version 20221018)
	(generator pcbnew)
	(general
    (thickness 1.518)
  )
	(paper "A4")
	(title_block
    (title "Kria K26 Devboard")
    (date "2024-03-26")
    (rev "1.2.5")
    (comment 1 "www.antmicro.com")
    (comment 2 "Antmicro Ltd.")
		(comment 9 "footprints 187-194 of 660")
	)
	(layers
    (0 "F.Cu" mixed)
    (1 "In1.Cu" power)
    (2 "In2.Cu" mixed)
    (3 "In3.Cu" power)
    (4 "In4.Cu" mixed)
    (5 "In5.Cu" power)
    (6 "In6.Cu" mixed)
    (31 "B.Cu" power)
    (32 "B.Adhes" user "B.Adhesive")
    (33 "F.Adhes" user "F.Adhesive")
    (34 "B.Paste" user)
    (35 "F.Paste" user)
    (36 "B.SilkS" user "B.Silkscreen")
    (37 "F.SilkS" user "F.Silkscreen")
    (38 "B.Mask" user)
    (39 "F.Mask" user)
    (40 "Dwgs.User" user "User.Drawings")
    (41 "Cmts.User" user "User.Comments")
    (42 "Eco1.User" user "User.Eco1")
    (43 "Eco2.User" user "User.Eco2")
    (44 "Edge.Cuts" user)
    (45 "Margin" user)
    (46 "B.CrtYd" user "B.Courtyard")
    (47 "F.CrtYd" user "F.Courtyard")
    (48 "B.Fab" user)
    (49 "F.Fab" user)
  )
	(footprint "kria-k26-devboard-footprints:Oscillator_SMD_ECS_2016MV_2x1.6x0.85mm" (layer "F.Cu")
    (at 142.719954 86.358222 90)
    (property "Author" "Antmicro")
    (property "License" "Apache-2.0")
    (property "MPN" "ECS-2016MV-250-CN-TR")
    (property "Manufacturer" "ECS Inc. International")
    (property "Sheetfile" "eth.kicad_sch")
    (property "Sheetname" "Ethernet")
    (property "VAL" "25 MHz")
    (property "Val" "25 MHz")
    (property "ki_description" "Oscillator, 25 MHz, HCMOS, SMD, 2mm x 1.6mm, MultiVolt ECS-2016MV Series")
    (property "ki_keywords" "OSCILLATOR")
    (attr smd)
    (fp_text reference "Y6" (at 1.118222 -1.419954) (layer "F.SilkS")
        (effects (font (size 0.7 0.7) (thickness 0.15)) (justify left bottom))
    )
    (fp_text value "Oscillator_25MHz_ESC_2016MV" (at 0 2.2 90) (layer "F.Fab") hide
        (effects (font (size 0.7 0.7) (thickness 0.15)) (justify left bottom))
    )
    (fp_text user "${REFERENCE}" (at -1.05 3.4 90) (layer "F.Fab") hide
        (effects (font (size 0.7 0.7) (thickness 0.15)) (justify left bottom))
    )
    (fp_text user "License: Apache-2.0" (at -1.05 5.8 90) (layer "F.Fab") hide
        (effects (font (size 0.7 0.7) (thickness 0.15)) (justify left bottom))
    )
    (fp_text user "Author: Antmicro" (at -1.05 4.6 90) (layer "F.Fab") hide
        (effects (font (size 0.7 0.7) (thickness 0.15)) (justify left bottom))
    )
    (fp_line (start -0.95 0.4) (end -0.95 -0.4)
      (stroke (width 0.15) (type solid)) (layer "F.SilkS"))
    (fp_line (start -0.4 -1.15) (end 0.4 -1.15)
      (stroke (width 0.15) (type solid)) (layer "F.SilkS"))
    (fp_line (start -0.4 1.15) (end 0.4 1.15)
      (stroke (width 0.15) (type solid)) (layer "F.SilkS"))
    (fp_line (start 0.95 0.4) (end 0.95 -0.4)
      (stroke (width 0.15) (type solid)) (layer "F.SilkS"))
    (fp_circle (center -0.95 -1.15) (end -0.9 -1.15)
      (stroke (width 0.15) (type solid)) (fill solid) (layer "F.SilkS"))
    (fp_rect (start -1.05 -1.25) (end 1.05 1.24)
      (stroke (width 0.05) (type solid)) (fill none) (layer "F.CrtYd"))
    (fp_rect (start -0.85 -1.054) (end 0.852 1.054)
      (stroke (width 0.15) (type solid)) (fill none) (layer "F.Fab"))
    (pad "1" smd rect (at -0.486 -0.637 90) (size 0.6858 0.7874) (layers "F.Cu" "F.Paste" "F.Mask")
      (net 803 "unconnected-(Y6-EN-Pad1)") (pinfunction "EN") (pintype "input+no_connect"))
    (pad "2" smd rect (at -0.486 0.636 90) (size 0.6858 0.7874) (layers "F.Cu" "F.Paste" "F.Mask")
      (net 1 "GND") (pinfunction "GND") (pintype "power_in"))
    (pad "3" smd rect (at 0.487 0.636 90) (size 0.6858 0.7874) (layers "F.Cu" "F.Paste" "F.Mask")
      (net 295 "/Ethernet/X_I") (pinfunction "OUT") (pintype "output"))
    (pad "4" smd rect (at 0.487 -0.637 90) (size 0.6858 0.7874) (layers "F.Cu" "F.Paste" "F.Mask")
      (net 17 "PS_1V8") (pinfunction "VDD") (pintype "power_in"))
  )
	(footprint "kria-k26-devboard-footprints:C_0402_1005Metric" (layer "F.Cu")
    (at 143.7 91.514035 180)
    (descr "Capacitor SMD 0402")
    (tags "capacitor SMD 0402")
    (property "Author" "Antmicro")
    (property "Dielectric" "X5R")
    (property "License" "Apache-2.0")
    (property "MPN" "GRM155R61H104KE14D")
    (property "Manufacturer" "Murata")
    (property "Sheetfile" "eth.kicad_sch")
    (property "Sheetname" "Ethernet")
    (property "Val" "100n")
    (property "Voltage" "50V")
    (property "ki_description" " ")
    (attr smd)
    (fp_text reference "C106" (at 1.42 -1.365965 180) (layer "F.SilkS")
        (effects (font (size 0.7 0.7) (thickness 0.15)) (justify left bottom))
    )
    (fp_text value "C_100n_0402" (at 0 1.4 180) (layer "F.Fab") hide
        (effects (font (size 0.7 0.7) (thickness 0.15)) (justify left bottom))
    )
    (fp_text user "${REFERENCE}" (at -0.932 3.168 180) (layer "F.Fab") hide
        (effects (font (size 0.7 0.7) (thickness 0.15)) (justify left bottom))
    )
    (fp_text user "License: Apache-2.0" (at -0.932 5.17 180) (layer "F.Fab") hide
        (effects (font (size 0.7 0.7) (thickness 0.15)) (justify left bottom))
    )
    (fp_text user "Author: Antmicro" (at -0.932 4.17 180) (layer "F.Fab") hide
        (effects (font (size 0.7 0.7) (thickness 0.15)) (justify left bottom))
    )
    (fp_rect (start -0.94 -0.47) (end 0.94 0.47)
      (stroke (width 0.05) (type solid)) (fill none) (layer "F.CrtYd"))
    (fp_rect (start -0.499 -0.249) (end 0.499 0.249)
      (stroke (width 0.15) (type solid)) (fill none) (layer "F.Fab"))
    (pad "1" smd roundrect (at -0.484 0 180) (size 0.59 0.64) (layers "F.Cu" "F.Paste" "F.Mask") (roundrect_rratio 0.25)
      (net 19 "PS_1V0") (pintype "passive"))
    (pad "2" smd roundrect (at 0.484 0 180) (size 0.59 0.64) (layers "F.Cu" "F.Paste" "F.Mask") (roundrect_rratio 0.25)
      (net 1 "GND") (pintype "passive"))
  )
	(footprint "kria-k26-devboard-footprints:R_0402_1005Metric" (layer "F.Cu")
    (at 154.161522 87.530152 180)
    (descr "Resistor SMD 0402")
    (tags "resistor SMD 0402")
    (property "Author" "Antmicro")
    (property "License" "Apache-2.0")
    (property "MPN" "CR0402-FX-2201GLF")
    (property "Manufacturer" "Bourns")
    (property "Sheetfile" "eth.kicad_sch")
    (property "Sheetname" "Ethernet")
    (property "Tolerance" "1%")
    (property "Val" "2k2")
    (property "ki_description" "2k2 resistor in 0402 package with 1% tolerance")
    (attr smd)
    (fp_text reference "R71" (at 0.681522 0.490152 180) (layer "F.SilkS")
        (effects (font (size 0.7 0.7) (thickness 0.15)) (justify left bottom))
    )
    (fp_text value "R_2k2_0402" (at 0 1.4 180) (layer "F.Fab") hide
        (effects (font (size 0.7 0.7) (thickness 0.15)) (justify left bottom))
    )
    (fp_text user "${REFERENCE}" (at -0.95 3.168 180) (layer "F.Fab") hide
        (effects (font (size 0.7 0.7) (thickness 0.15)) (justify left bottom))
    )
    (fp_text user "License: Apache-2.0" (at -0.95 5.169 180) (layer "F.Fab") hide
        (effects (font (size 0.7 0.7) (thickness 0.15)) (justify left bottom))
    )
    (fp_text user "Author: Antmicro" (at -0.95 4.169 180) (layer "F.Fab") hide
        (effects (font (size 0.7 0.7) (thickness 0.15)) (justify left bottom))
    )
    (fp_rect (start -0.93 -0.47) (end 0.93 0.47)
      (stroke (width 0.05) (type solid)) (fill none) (layer "F.CrtYd"))
    (fp_rect (start -0.5 -0.25) (end 0.5 0.25)
      (stroke (width 0.15) (type solid)) (fill none) (layer "F.Fab"))
    (pad "1" smd roundrect (at -0.485 0 180) (size 0.59 0.64) (layers "F.Cu" "F.Paste" "F.Mask") (roundrect_rratio 0.25)
      (net 17 "PS_1V8") (pintype "passive"))
    (pad "2" smd roundrect (at 0.485 0 180) (size 0.59 0.64) (layers "F.Cu" "F.Paste" "F.Mask") (roundrect_rratio 0.25)
      (net 670 "Net-(U30-INT_PWDN)") (pintype "passive"))
  )
	(footprint "kria-k26-devboard-footprints:R_0402_1005Metric" (layer "F.Cu")
    (at 145.24 83.95 90)
    (descr "Resistor SMD 0402")
    (tags "resistor SMD 0402")
    (property "Author" "Antmicro")
    (property "License" "Apache-2.0")
    (property "MPN" "CR0402-FX-1102GLF")
    (property "Manufacturer" "Bourns")
    (property "Sheetfile" "eth.kicad_sch")
    (property "Sheetname" "Ethernet")
    (property "Tolerance" "1%")
    (property "Val" "11k")
    (property "ki_description" "11k resistor in 0402 package with 1% tolerance")
    (attr smd)
    (fp_text reference "R72" (at -0.952159 -0.649464 90) (layer "F.SilkS")
        (effects (font (size 0.7 0.7) (thickness 0.15)) (justify left bottom))
    )
    (fp_text value "R_11k_0402" (at 0 1.4 90) (layer "F.Fab") hide
        (effects (font (size 0.7 0.7) (thickness 0.15)) (justify left bottom))
    )
    (fp_text user "License: Apache-2.0" (at -0.95 5.169 90) (layer "F.Fab") hide
        (effects (font (size 0.7 0.7) (thickness 0.15)) (justify left bottom))
    )
    (fp_text user "${REFERENCE}" (at -0.95 3.168 90) (layer "F.Fab") hide
        (effects (font (size 0.7 0.7) (thickness 0.15)) (justify left bottom))
    )
    (fp_text user "Author: Antmicro" (at -0.95 4.169 90) (layer "F.Fab") hide
        (effects (font (size 0.7 0.7) (thickness 0.15)) (justify left bottom))
    )
    (fp_rect (start -0.93 -0.47) (end 0.93 0.47)
      (stroke (width 0.05) (type solid)) (fill none) (layer "F.CrtYd"))
    (fp_rect (start -0.5 -0.25) (end 0.5 0.25)
      (stroke (width 0.15) (type solid)) (fill none) (layer "F.Fab"))
    (pad "1" smd roundrect (at -0.485 0 90) (size 0.59 0.64) (layers "F.Cu" "F.Paste" "F.Mask") (roundrect_rratio 0.25)
      (net 671 "Net-(U30-RBIAS)") (pintype "passive"))
    (pad "2" smd roundrect (at 0.485 0 90) (size 0.59 0.64) (layers "F.Cu" "F.Paste" "F.Mask") (roundrect_rratio 0.25)
      (net 1 "GND") (pintype "passive"))
  )
	(footprint "kria-k26-devboard-footprints:SOT-416" (layer "F.Cu")
    (at 154.73 70.1 90)
    (descr "SOT-416")
    (tags "SOT-416")
    (property "Author" "Antmicro")
    (property "License" "Apache-2.0")
    (property "MPN" "DTC014TEBTL")
    (property "Manufacturer" "ROHM Semiconductor")
    (property "Sheetfile" "eth.kicad_sch")
    (property "Sheetname" "Ethernet")
    (property "ki_description" "Digital NPN Transistor, 10k/NONE, EMT-3")
    (attr smd)
    (fp_text reference "Q4" (at -1.9 -0.84 180) (layer "F.SilkS")
        (effects (font (size 0.7 0.7) (thickness 0.15)) (justify left bottom))
    )
    (fp_text value "DTC014T_SOT-416" (at 0 2 90) (layer "F.Fab") hide
        (effects (font (size 0.7 0.7) (thickness 0.15)) (justify left bottom))
    )
    (fp_text user "${REFERENCE}" (at -1 3.4 90) (layer "F.Fab") hide
        (effects (font (size 0.7 0.7) (thickness 0.15)) (justify left bottom))
    )
    (fp_text user "License: Apache-2.0" (at -1 5.802 90) (layer "F.Fab") hide
        (effects (font (size 0.7 0.7) (thickness 0.15)) (justify left bottom))
    )
    (fp_text user "Author: Antmicro" (at -1 4.602 90) (layer "F.Fab") hide
        (effects (font (size 0.7 0.7) (thickness 0.15)) (justify left bottom))
    )
    (fp_line (start -0.5 -0.15) (end -0.5 0.15)
      (stroke (width 0.15) (type solid)) (layer "F.SilkS"))
    (fp_line (start 0.5 0.9) (end -0.5 0.9)
      (stroke (width 0.15) (type solid)) (layer "F.SilkS"))
    (fp_line (start 0.5 0.9) (end 0.5 0.7)
      (stroke (width 0.15) (type solid)) (layer "F.SilkS"))
    (fp_line (start 0.508 -0.9) (end -0.5 -0.9)
      (stroke (width 0.15) (type solid)) (layer "F.SilkS"))
    (fp_line (start 0.508 -0.9) (end 0.508 -0.592)
      (stroke (width 0.15) (type solid)) (layer "F.SilkS"))
    (fp_rect (start -1 -1.05) (end 1 1.05)
      (stroke (width 0.05) (type solid)) (fill none) (layer "F.CrtYd"))
    (fp_line (start -0.05 -0.9) (end -0.45 -0.5)
      (stroke (width 0.15) (type solid)) (layer "F.Fab"))
    (fp_rect (start 0.45 0.9) (end -0.45 -0.9)
      (stroke (width 0.15) (type solid)) (fill none) (layer "F.Fab"))
    (pad "1" smd rect (at -0.652 -0.5 90) (size 0.6 0.5) (layers "F.Cu" "F.Paste" "F.Mask")
      (net 364 "/Ethernet/LED0") (pinfunction "B") (pintype "input"))
    (pad "2" smd rect (at -0.652 0.498 90) (size 0.6 0.5) (layers "F.Cu" "F.Paste" "F.Mask")
      (net 1 "GND") (pinfunction "E") (pintype "passive"))
    (pad "3" smd rect (at 0.65 0 90) (size 0.6 0.5) (layers "F.Cu" "F.Paste" "F.Mask")
      (net 351 "Net-(J5-LED_GRN-)") (pinfunction "C") (pintype "passive"))
  )
	(footprint "kria-k26-devboard-footprints:SOT-416" (layer "F.Cu")
    (at 152.62 70.1 90)
    (descr "SOT-416")
    (tags "SOT-416")
    (property "Author" "Antmicro")
    (property "License" "Apache-2.0")
    (property "MPN" "DTC014TEBTL")
    (property "Manufacturer" "ROHM Semiconductor")
    (property "Sheetfile" "eth.kicad_sch")
    (property "Sheetname" "Ethernet")
    (property "ki_description" "Digital NPN Transistor, 10k/NONE, EMT-3")
    (attr smd)
    (fp_text reference "Q5" (at -1.88 -0.72 180) (layer "F.SilkS")
        (effects (font (size 0.7 0.7) (thickness 0.15)) (justify left bottom))
    )
    (fp_text value "DTC014T_SOT-416" (at 0 2 90) (layer "F.Fab") hide
        (effects (font (size 0.7 0.7) (thickness 0.15)) (justify left bottom))
    )
    (fp_text user "${REFERENCE}" (at -1 3.4 90) (layer "F.Fab") hide
        (effects (font (size 0.7 0.7) (thickness 0.15)) (justify left bottom))
    )
    (fp_text user "Author: Antmicro" (at -1 4.602 90) (layer "F.Fab") hide
        (effects (font (size 0.7 0.7) (thickness 0.15)) (justify left bottom))
    )
    (fp_text user "License: Apache-2.0" (at -1 5.802 90) (layer "F.Fab") hide
        (effects (font (size 0.7 0.7) (thickness 0.15)) (justify left bottom))
    )
    (fp_line (start -0.5 -0.15) (end -0.5 0.15)
      (stroke (width 0.15) (type solid)) (layer "F.SilkS"))
    (fp_line (start 0.5 0.9) (end -0.5 0.9)
      (stroke (width 0.15) (type solid)) (layer "F.SilkS"))
    (fp_line (start 0.5 0.9) (end 0.5 0.7)
      (stroke (width 0.15) (type solid)) (layer "F.SilkS"))
    (fp_line (start 0.508 -0.9) (end -0.5 -0.9)
      (stroke (width 0.15) (type solid)) (layer "F.SilkS"))
    (fp_line (start 0.508 -0.9) (end 0.508 -0.592)
      (stroke (width 0.15) (type solid)) (layer "F.SilkS"))
    (fp_rect (start -1 -1.05) (end 1 1.05)
      (stroke (width 0.05) (type solid)) (fill none) (layer "F.CrtYd"))
    (fp_line (start -0.05 -0.9) (end -0.45 -0.5)
      (stroke (width 0.15) (type solid)) (layer "F.Fab"))
    (fp_rect (start 0.45 0.9) (end -0.45 -0.9)
      (stroke (width 0.15) (type solid)) (fill none) (layer "F.Fab"))
    (pad "1" smd rect (at -0.652 -0.5 90) (size 0.6 0.5) (layers "F.Cu" "F.Paste" "F.Mask")
      (net 51 "/Ethernet/LED2") (pinfunction "B") (pintype "input"))
    (pad "2" smd rect (at -0.652 0.498 90) (size 0.6 0.5) (layers "F.Cu" "F.Paste" "F.Mask")
      (net 1 "GND") (pinfunction "E") (pintype "passive"))
    (pad "3" smd rect (at 0.65 0 90) (size 0.6 0.5) (layers "F.Cu" "F.Paste" "F.Mask")
      (net 353 "Net-(J5-LED_YEL-)") (pinfunction "C") (pintype "passive"))
  )
	(footprint "kria-k26-devboard-footprints:R_0402_1005Metric" (layer "F.Cu")
    (at 131.8 118)
    (descr "Resistor SMD 0402")
    (tags "resistor SMD 0402")
    (property "Author" "Antmicro")
    (property "License" "Apache-2.0")
    (property "MPN" "CR0402-FX-1002GLF")
    (property "Manufacturer" "Bourns")
    (property "Sheetfile" "pcie-m2-key-e.kicad_sch")
    (property "Sheetname" "PCIE M2 key E ")
    (property "Tolerance" "1%")
    (property "Val" "10k")
    (property "ki_description" "10k resistor in 0402 package with 1% tolerance")
    (attr smd)
    (fp_text reference "R151" (at -1.27 -1.56) (layer "F.SilkS")
        (effects (font (size 0.7 0.7) (thickness 0.15)) (justify left bottom))
    )
    (fp_text value "R_10k_0402" (at 0 1.4) (layer "F.Fab") hide
        (effects (font (size 0.7 0.7) (thickness 0.15)) (justify left bottom))
    )
    (fp_text user "Author: Antmicro" (at -0.95 4.169) (layer "F.Fab") hide
        (effects (font (size 0.7 0.7) (thickness 0.15)) (justify left bottom))
    )
    (fp_text user "License: Apache-2.0" (at -0.95 5.169) (layer "F.Fab") hide
        (effects (font (size 0.7 0.7) (thickness 0.15)) (justify left bottom))
    )
    (fp_text user "${REFERENCE}" (at -0.95 3.168) (layer "F.Fab") hide
        (effects (font (size 0.7 0.7) (thickness 0.15)) (justify left bottom))
    )
    (fp_rect (start -0.93 -0.47) (end 0.93 0.47)
      (stroke (width 0.05) (type solid)) (fill none) (layer "F.CrtYd"))
    (fp_rect (start -0.5 -0.25) (end 0.5 0.25)
      (stroke (width 0.15) (type solid)) (fill none) (layer "F.Fab"))
    (pad "1" smd roundrect (at -0.485 0) (size 0.59 0.64) (layers "F.Cu" "F.Paste" "F.Mask") (roundrect_rratio 0.25)
      (net 15 "PS_3V3") (pintype "passive"))
    (pad "2" smd roundrect (at 0.485 0) (size 0.59 0.64) (layers "F.Cu" "F.Paste" "F.Mask") (roundrect_rratio 0.25)
      (net 396 "Net-(J12-~{CLKREQ0})") (pintype "passive"))
  )
	(footprint "kria-k26-devboard-footprints:Nexperia_SOD128" (layer "F.Cu")
    (at 143.675 66.65 180)
    (property "Author" "Antmicro")
    (property "DNP" "DNP")
    (property "License" "Apache-2.0")
    (property "MPN" "PMEG3050EP,115")
    (property "Manufacturer" "Nexperia")
    (property "Sheetfile" "supply-oring.kicad_sch")
    (property "Sheetname" "Supply ORing")
    (property "dnp" "")
    (property "exclude_from_bom" "")
    (property "ki_description" "SCHOTTKY RECT 30V 5A, Vf=315 mV")
    (attr exclude_from_pos_files exclude_from_bom)
    (fp_text reference "D24" (at 2.235 -2.45 180) (layer "F.SilkS")
        (effects (font (size 0.7 0.7) (thickness 0.15)) (justify left bottom))
    )
    (fp_text value "PMEG3050EP,115" (at -4.37 2.5 180) (layer "F.Fab") hide
        (effects (font (size 0.7 0.7) (thickness 0.15)) (justify left bottom))
    )
    (fp_text user "${REFERENCE}" (at -4.37 6.9 180) (layer "F.Fab") hide
        (effects (font (size 0.7 0.7) (thickness 0.15)) (justify left bottom))
    )
    (fp_text user "Author: Antmicro" (at -4.37 4.5 180) (layer "F.Fab") hide
        (effects (font (size 0.7 0.7) (thickness 0.15)) (justify left bottom))
    )
    (fp_text user "License: Apache-2.0" (at -4.37 5.7 180) (layer "F.Fab") hide
        (effects (font (size 0.7 0.7) (thickness 0.15)) (justify left bottom))
    )
    (fp_line (start -2.121 -1.474) (end -2.121 -1.287)
      (stroke (width 0.15) (type solid)) (layer "F.SilkS"))
    (fp_line (start -2.121 1.284) (end -2.121 1.473)
      (stroke (width 0.15) (type solid)) (layer "F.SilkS"))
    (fp_line (start -2.121 1.473) (end 2.12 1.473)
      (stroke (width 0.15) (type solid)) (layer "F.SilkS"))
    (fp_line (start -1.6 -1.4) (end -1.6 1.4)
      (stroke (width 0.12) (type solid)) (layer "F.SilkS"))
    (fp_line (start 2.12 -1.474) (end -2.121 -1.474)
      (stroke (width 0.15) (type solid)) (layer "F.SilkS"))
    (fp_line (start 2.12 -1.287) (end 2.12 -1.474)
      (stroke (width 0.15) (type solid)) (layer "F.SilkS"))
    (fp_line (start 2.12 1.473) (end 2.12 1.284)
      (stroke (width 0.15) (type solid)) (layer "F.SilkS"))
    (fp_rect (start -2.8 -1.6) (end 2.8 1.6)
      (stroke (width 0.05) (type solid)) (fill none) (layer "F.CrtYd"))
    (fp_line (start -2.503 -0.954) (end -2.503 0.952)
      (stroke (width 0.15) (type solid)) (layer "F.Fab"))
    (fp_line (start -2.503 0.952) (end -1.994 0.952)
      (stroke (width 0.15) (type solid)) (layer "F.Fab"))
    (fp_line (start -1.994 -1.347) (end -1.994 1.346)
      (stroke (width 0.15) (type solid)) (layer "F.Fab"))
    (fp_line (start -1.994 -0.954) (end -2.503 -0.954)
      (stroke (width 0.15) (type solid)) (layer "F.Fab"))
    (fp_line (start -1.994 -0.675) (end -1.321 -1.347)
      (stroke (width 0.15) (type solid)) (layer "F.Fab"))
    (fp_line (start -1.994 0.673) (end -1.321 1.346)
      (stroke (width 0.15) (type solid)) (layer "F.Fab"))
    (fp_line (start -1.994 0.952) (end -1.994 -0.954)
      (stroke (width 0.15) (type solid)) (layer "F.Fab"))
    (fp_line (start -1.994 1.346) (end 1.993 1.346)
      (stroke (width 0.15) (type solid)) (layer "F.Fab"))
    (fp_line (start 1.993 -1.347) (end -1.994 -1.347)
      (stroke (width 0.15) (type solid)) (layer "F.Fab"))
    (fp_line (start 1.993 -0.954) (end 1.993 0.952)
      (stroke (width 0.15) (type solid)) (layer "F.Fab"))
    (fp_line (start 1.993 0.952) (end 2.5 0.952)
      (stroke (width 0.15) (type solid)) (layer "F.Fab"))
    (fp_line (start 1.993 1.346) (end 1.993 -1.347)
      (stroke (width 0.15) (type solid)) (layer "F.Fab"))
    (fp_line (start 2.5 -0.954) (end 1.993 -0.954)
      (stroke (width 0.15) (type solid)) (layer "F.Fab"))
    (fp_line (start 2.5 0.952) (end 2.5 -0.954)
      (stroke (width 0.15) (type solid)) (layer "F.Fab"))
    (pad "1" smd rect (at -2.298 0 180) (size 0.8096 1.905) (layers "F.Cu" "F.Paste" "F.Mask")
      (net 14 "/Power Supply/DC/DC conventers/DC_MAIN_BUS") (pinfunction "1") (pintype "passive"))
    (pad "2" smd rect (at 2.297 0 180) (size 0.8096 1.905) (layers "F.Cu" "F.Paste" "F.Mask")
      (net 228 "/Power Supply/Supply ORing/PD_VBUS") (pinfunction "2") (pintype "passive"))
  )
)
